(kicad_pcb
	(version 20260206)
	(generator "pcbnew")
	(generator_version "10.0")
	(general
		(thickness 1.6)
		(legacy_teardrops no)
	)
	(paper "A4")
	(title_block
		(title "03242023_DA0F0TMBIJ0_F0T_Motherboard_J_brd_V01_OCP.brd")
		(comment 1 "Grand Teton / footprint 3039 of 6105 (U2), pads 2363-2476 of 4677")
	)
	(layers
		(0 "F.Cu" signal "TOP")
		(4 "In1.Cu" signal "GND")
		(6 "In2.Cu" signal "IN1")
		(8 "In3.Cu" signal "GND1")
		(10 "In4.Cu" signal "IN2")
		(12 "In5.Cu" signal "GND2")
		(14 "In6.Cu" signal "IN3")
		(16 "In7.Cu" signal "GND3")
		(18 "In8.Cu" signal "VCC")
		(20 "In9.Cu" signal "VCC1")
		(22 "In10.Cu" signal "GND4")
		(24 "In11.Cu" signal "IN4")
		(26 "In12.Cu" signal "GND5")
		(28 "In13.Cu" signal "IN5")
		(30 "In14.Cu" signal "GND6")
		(32 "In15.Cu" signal "IN6")
		(34 "In16.Cu" signal "GND7")
		(2 "B.Cu" signal "BOTTOM")
		(9 "F.Adhes" user "F.Adhesive")
		(11 "B.Adhes" user "B.Adhesive")
		(13 "F.Paste" user "Package Geometry/Pastemask Top")
		(15 "B.Paste" user "Package Geometry/Pastemask Bottom")
		(5 "F.SilkS" user "Ref Des/Silkscreen Top")
		(7 "B.SilkS" user "Ref Des/Silkscreen Bottom")
		(1 "F.Mask" user "Board Geometry/Soldermask Top")
		(3 "B.Mask" user "Board Geometry/Soldermask Bottom")
		(17 "Dwgs.User" user "User.Drawings")
		(19 "Cmts.User" user "User.Comments")
		(21 "Eco1.User" user "User.Eco1")
		(23 "Eco2.User" user "User.Eco2")
		(25 "Edge.Cuts" user "Board Geometry/Outline")
		(27 "Margin" user)
		(31 "F.CrtYd" user "Package Geometry/Place Bound Top")
		(29 "B.CrtYd" user "Package Geometry/Place Bound Bottom")
		(35 "F.Fab" user "Ref Des/Assembly Top")
		(33 "B.Fab" user "Ref Des/Assembly Bottom")
	)
	(footprint ""
		(layer "F.Cu")
		(at 359.870248 -251.76988 90)
		(property "Reference" "U2"
			(at -74.416158 -44.488608 0)
			(unlocked yes)
			(layer "F.SilkS")
			(effects
				(font
					(size 1.6002 1.1938)
					(thickness 0.1524)
				)
				(justify left)
			)
		)
		(property "Value" ""
			(at 0 0 90)
			(layer "F.Fab")
			(effects
				(font
					(size 1.27 1.27)
				)
			)
		)
		(duplicate_pad_numbers_are_jumpers no)
		(pad "D32" smd circle
			(at -12.19454 -25.664414 270)
			(size 0.4318 0.4318)
			(layers "F.Cu" "F.Mask" "F.Paste")
			(net "GND")
		)
		(pad "D34" smd circle
			(at -10.566654 -25.664414 270)
			(size 0.4318 0.4318)
			(layers "F.Cu" "F.Mask" "F.Paste")
			(net "GND")
		)
		(pad "D36" smd circle
			(at -8.939022 -25.664414 270)
			(size 0.4318 0.4318)
			(layers "F.Cu" "F.Mask" "F.Paste")
			(net "GND")
		)
		(pad "D38" smd circle
			(at -7.311136 -25.664414 270)
			(size 0.4318 0.4318)
			(layers "F.Cu" "F.Mask" "F.Paste")
			(net "GND")
		)
		(pad "D40" smd circle
			(at -5.68325 -25.664414 270)
			(size 0.4318 0.4318)
			(layers "F.Cu" "F.Mask" "F.Paste")
			(net "GND")
		)
		(pad "D42" smd circle
			(at -4.055618 -25.664414 270)
			(size 0.4318 0.4318)
			(layers "F.Cu" "F.Mask" "F.Paste")
			(net "GND")
		)
		(pad "D44" smd circle
			(at -2.427732 -25.664414 270)
			(size 0.4318 0.4318)
			(layers "F.Cu" "F.Mask" "F.Paste")
			(net "GND")
		)
		(pad "D47" smd oval
			(at 1.613916 -25.554686 135)
			(size 0.381 0.4826)
			(drill
				(offset 0 -0.0508)
			)
			(layers "F.Cu" "F.Mask" "F.Paste")
			(net "GND")
		)
		(pad "D49" smd circle
			(at 3.241802 -25.554686 270)
			(size 0.4318 0.4318)
			(layers "F.Cu" "F.Mask" "F.Paste")
			(net "GND")
		)
		(pad "D51" smd circle
			(at 4.869434 -25.554686 270)
			(size 0.4318 0.4318)
			(layers "F.Cu" "F.Mask" "F.Paste")
			(net "GND")
		)
		(pad "D53" smd circle
			(at 6.49732 -25.554686 270)
			(size 0.4318 0.4318)
			(layers "F.Cu" "F.Mask" "F.Paste")
			(net "GND")
		)
		(pad "D55" smd circle
			(at 8.124952 -25.554686 270)
			(size 0.4318 0.4318)
			(layers "F.Cu" "F.Mask" "F.Paste")
			(net "GND")
		)
		(pad "D57" smd circle
			(at 9.752838 -25.554686 270)
			(size 0.4318 0.4318)
			(layers "F.Cu" "F.Mask" "F.Paste")
			(net "GND")
		)
		(pad "D59" smd circle
			(at 11.380724 -25.554686 270)
			(size 0.4318 0.4318)
			(layers "F.Cu" "F.Mask" "F.Paste")
			(net "GND")
		)
		(pad "D61" smd circle
			(at 13.008356 -25.554686 270)
			(size 0.4318 0.4318)
			(layers "F.Cu" "F.Mask" "F.Paste")
			(net "GND")
		)
		(pad "D63" smd circle
			(at 14.635988 -25.554686 270)
			(size 0.4318 0.4318)
			(layers "F.Cu" "F.Mask" "F.Paste")
			(net "GND")
		)
		(pad "D65" smd circle
			(at 16.263874 -25.554686 270)
			(size 0.4318 0.4318)
			(layers "F.Cu" "F.Mask" "F.Paste")
			(net "GND")
		)
		(pad "D67" smd circle
			(at 17.89176 -25.554686 270)
			(size 0.4318 0.4318)
			(layers "F.Cu" "F.Mask" "F.Paste")
			(net "GND")
		)
		(pad "D69" smd circle
			(at 19.519392 -25.554686 270)
			(size 0.4318 0.4318)
			(layers "F.Cu" "F.Mask" "F.Paste")
			(net "GND")
		)
		(pad "D71" smd circle
			(at 21.147278 -25.554686 270)
			(size 0.4318 0.4318)
			(layers "F.Cu" "F.Mask" "F.Paste")
			(net "GND")
		)
		(pad "D73" smd circle
			(at 22.77491 -25.554686 270)
			(size 0.4318 0.4318)
			(layers "F.Cu" "F.Mask" "F.Paste")
			(net "M_A_CPU0_SA_DQ<18>")
		)
		(pad "D75" smd circle
			(at 24.402796 -25.554686 270)
			(size 0.4318 0.4318)
			(layers "F.Cu" "F.Mask" "F.Paste")
			(net "M_A_CPU0_SA_DQ<5>")
		)
		(pad "D77" smd circle
			(at 26.030682 -25.554686 270)
			(size 0.4318 0.4318)
			(layers "F.Cu" "F.Mask" "F.Paste")
			(net "M_A_CPU0_SA_DQS_DP<0>")
		)
		(pad "D79" smd circle
			(at 27.658314 -25.554686 270)
			(size 0.4318 0.4318)
			(layers "F.Cu" "F.Mask" "F.Paste")
			(net "GND")
		)
		(pad "D81" smd circle
			(at 29.2862 -25.554686 270)
			(size 0.4318 0.4318)
			(layers "F.Cu" "F.Mask" "F.Paste")
			(net "GND")
		)
		(pad "D83" smd circle
			(at 30.914086 -25.554686 270)
			(size 0.4318 0.4318)
			(layers "F.Cu" "F.Mask" "F.Paste")
			(net "GND")
		)
		(pad "D85" smd oval
			(at 32.541718 -25.554686 45)
			(size 0.381 0.4826)
			(drill
				(offset 0 -0.0508)
			)
			(layers "F.Cu" "F.Mask" "F.Paste")
			(net "UPI_CPU0_CPU1_P2P2_DP<23>")
		)
		(pad "D87" smd oval
			(at 34.169604 -25.554686 45)
			(size 0.381 0.4826)
			(drill
				(offset 0 -0.0508)
			)
			(layers "F.Cu" "F.Mask" "F.Paste")
			(net "UPI_CPU0_CPU1_P2P2_DN<21>")
		)
		(pad "DA1" smd oval
			(at -37.425122 10.517886 180)
			(size 0.381 0.4826)
			(drill
				(offset 0 -0.0508)
			)
			(layers "F.Cu" "F.Mask" "F.Paste")
			(net "UPI_CPU1_CPU0_P0P1_DP<13>")
		)
		(pad "DA3" smd circle
			(at -35.797236 10.517886 270)
			(size 0.4318 0.4318)
			(layers "F.Cu" "F.Mask" "F.Paste")
			(net "PVCCINFAON_CPU0")
		)
		(pad "DA5" smd circle
			(at -34.169604 10.517886 270)
			(size 0.4318 0.4318)
			(layers "F.Cu" "F.Mask" "F.Paste")
			(net "UPI_CPU0_CPU1_P1P0_DP<12>")
		)
		(pad "DA7" smd circle
			(at -32.541718 10.517886 270)
			(size 0.4318 0.4318)
			(layers "F.Cu" "F.Mask" "F.Paste")
			(net "PVCCINFAON_CPU0")
		)
		(pad "DA9" smd circle
			(at -30.914086 10.517886 270)
			(size 0.4318 0.4318)
			(layers "F.Cu" "F.Mask" "F.Paste")
			(net "P5E_CPU0_PE2_RX_DN<2>")
		)
		(pad "DA11" smd circle
			(at -29.2862 10.517886 270)
			(size 0.4318 0.4318)
			(layers "F.Cu" "F.Mask" "F.Paste")
			(net "PVCCINFAON_CPU0")
		)
		(pad "DA13" smd circle
			(at -27.658314 10.517886 270)
			(size 0.4318 0.4318)
			(layers "F.Cu" "F.Mask" "F.Paste")
			(net "P5E_CPU0_PE2_TX_DN<2>")
		)
		(pad "DA15" smd circle
			(at -26.030682 10.517886 270)
			(size 0.4318 0.4318)
			(layers "F.Cu" "F.Mask" "F.Paste")
			(net "PVCCINFAON_CPU0")
		)
		(pad "DA17" smd circle
			(at -24.402796 10.517886 270)
			(size 0.4318 0.4318)
			(layers "F.Cu" "F.Mask" "F.Paste")
			(net "M_H_CPU0_SB_DQ<29>")
		)
		(pad "DA19" smd circle
			(at -22.77491 10.517886 270)
			(size 0.4318 0.4318)
			(layers "F.Cu" "F.Mask" "F.Paste")
			(net "GND")
		)
		(pad "DA21" smd circle
			(at -21.147278 10.517886 270)
			(size 0.4318 0.4318)
			(layers "F.Cu" "F.Mask" "F.Paste")
			(net "PVCCINFAON_CPU0")
		)
		(pad "DA23" smd circle
			(at -19.519392 10.517886 270)
			(size 0.4318 0.4318)
			(layers "F.Cu" "F.Mask" "F.Paste")
			(net "GND")
		)
		(pad "DA25" smd circle
			(at -17.89176 10.517886 270)
			(size 0.4318 0.4318)
			(layers "F.Cu" "F.Mask" "F.Paste")
			(net "GND")
		)
		(pad "DA27" smd circle
			(at -16.263874 10.517886 270)
			(size 0.4318 0.4318)
			(layers "F.Cu" "F.Mask" "F.Paste")
			(net "CLK_100M_DB2000_CPU0_BCLK3_DP")
		)
		(pad "DA29" smd circle
			(at -14.635988 10.517886 270)
			(size 0.4318 0.4318)
			(layers "F.Cu" "F.Mask" "F.Paste")
			(net "GND")
		)
		(pad "DA31" smd circle
			(at -13.008356 10.517886 270)
			(size 0.4318 0.4318)
			(layers "F.Cu" "F.Mask" "F.Paste")
			(net "GND")
		)
		(pad "DA33" smd circle
			(at -11.380724 10.517886 270)
			(size 0.4318 0.4318)
			(layers "F.Cu" "F.Mask" "F.Paste")
			(net "GND")
		)
		(pad "DA35" smd circle
			(at -9.752838 10.517886 270)
			(size 0.4318 0.4318)
			(layers "F.Cu" "F.Mask" "F.Paste")
			(net "GND")
		)
		(pad "DA37" smd circle
			(at -8.124952 10.517886 270)
			(size 0.4318 0.4318)
			(layers "F.Cu" "F.Mask" "F.Paste")
			(net "GND")
		)
		(pad "DA39" smd circle
			(at -6.49732 10.517886 270)
			(size 0.4318 0.4318)
			(layers "F.Cu" "F.Mask" "F.Paste")
			(net "H_CPU0_PMSYNC_PCH")
		)
		(pad "DA41" smd circle
			(at -4.869434 10.517886 270)
			(size 0.4318 0.4318)
			(layers "F.Cu" "F.Mask" "F.Paste")
			(net "GND")
		)
		(pad "DA43" smd circle
			(at -3.241802 10.517886 270)
			(size 0.4318 0.4318)
			(layers "F.Cu" "F.Mask" "F.Paste")
			(net "GND")
		)
		(pad "DA45" smd circle
			(at -1.613916 10.517886 270)
			(size 0.4318 0.4318)
			(layers "F.Cu" "F.Mask" "F.Paste")
			(net "NC_CPU0_DDR67_VIEWDIG0")
		)
		(pad "DA48" smd circle
			(at 2.427732 10.627868 270)
			(size 0.4318 0.4318)
			(layers "F.Cu" "F.Mask" "F.Paste")
			(net "GND")
		)
		(pad "DA50" smd circle
			(at 4.055618 10.627868 270)
			(size 0.4318 0.4318)
			(layers "F.Cu" "F.Mask" "F.Paste")
			(net "GND")
		)
		(pad "DA52" smd circle
			(at 5.68325 10.627868 270)
			(size 0.4318 0.4318)
			(layers "F.Cu" "F.Mask" "F.Paste")
			(net "TP_CPU0_PROCDIS_COD_GTL_N")
		)
		(pad "DA54" smd circle
			(at 7.311136 10.627868 270)
			(size 0.4318 0.4318)
			(layers "F.Cu" "F.Mask" "F.Paste")
			(net "GND")
		)
		(pad "DA56" smd circle
			(at 8.939022 10.627868 270)
			(size 0.4318 0.4318)
			(layers "F.Cu" "F.Mask" "F.Paste")
			(net "GND")
		)
		(pad "DA58" smd circle
			(at 10.566654 10.627868 270)
			(size 0.4318 0.4318)
			(layers "F.Cu" "F.Mask" "F.Paste")
			(net "GND")
		)
		(pad "DA60" smd circle
			(at 12.19454 10.627868 270)
			(size 0.4318 0.4318)
			(layers "F.Cu" "F.Mask" "F.Paste")
			(net "GND")
		)
		(pad "DA62" smd circle
			(at 13.822426 10.627868 270)
			(size 0.4318 0.4318)
			(layers "F.Cu" "F.Mask" "F.Paste")
			(net "GND")
		)
		(pad "DA64" smd circle
			(at 15.450058 10.627868 270)
			(size 0.4318 0.4318)
			(layers "F.Cu" "F.Mask" "F.Paste")
			(net "PVCCINFAON_CPU0")
		)
		(pad "DA66" smd circle
			(at 17.07769 10.627868 270)
			(size 0.4318 0.4318)
			(layers "F.Cu" "F.Mask" "F.Paste")
			(net "GND")
		)
		(pad "DA68" smd circle
			(at 18.705576 10.627868 270)
			(size 0.4318 0.4318)
			(layers "F.Cu" "F.Mask" "F.Paste")
			(net "GND")
		)
		(pad "DA70" smd circle
			(at 20.333462 10.627868 270)
			(size 0.4318 0.4318)
			(layers "F.Cu" "F.Mask" "F.Paste")
			(net "TP_CPU0_SPARE4")
		)
		(pad "DA72" smd circle
			(at 21.961094 10.627868 270)
			(size 0.4318 0.4318)
			(layers "F.Cu" "F.Mask" "F.Paste")
			(net "GND")
		)
		(pad "DA74" smd circle
			(at 23.58898 10.627868 270)
			(size 0.4318 0.4318)
			(layers "F.Cu" "F.Mask" "F.Paste")
			(net "GND")
		)
		(pad "DA76" smd circle
			(at 25.216612 10.627868 270)
			(size 0.4318 0.4318)
			(layers "F.Cu" "F.Mask" "F.Paste")
			(net "Net_673")
		)
		(pad "DA78" smd circle
			(at 26.844498 10.627868 270)
			(size 0.4318 0.4318)
			(layers "F.Cu" "F.Mask" "F.Paste")
			(net "GND")
		)
		(pad "DA80" smd circle
			(at 28.472384 10.627868 270)
			(size 0.4318 0.4318)
			(layers "F.Cu" "F.Mask" "F.Paste")
			(net "GND")
		)
		(pad "DA82" smd circle
			(at 30.100016 10.627868 270)
			(size 0.4318 0.4318)
			(layers "F.Cu" "F.Mask" "F.Paste")
			(net "GND")
		)
		(pad "DA84" smd circle
			(at 31.727902 10.627868 270)
			(size 0.4318 0.4318)
			(layers "F.Cu" "F.Mask" "F.Paste")
			(net "GND")
		)
		(pad "DA86" smd circle
			(at 33.355534 10.627868 270)
			(size 0.4318 0.4318)
			(layers "F.Cu" "F.Mask" "F.Paste")
			(net "P5E_CPU0_PE3_TX_DP<12>")
		)
		(pad "DA88" smd circle
			(at 34.98342 10.627868 270)
			(size 0.4318 0.4318)
			(layers "F.Cu" "F.Mask" "F.Paste")
			(net "GND")
		)
		(pad "DA90" smd circle
			(at 36.611306 10.627868 270)
			(size 0.4318 0.4318)
			(layers "F.Cu" "F.Mask" "F.Paste")
			(net "P5E_CPU0_PE3_RX_DN<13>")
		)
		(pad "DB2" smd circle
			(at -36.611306 10.987532 270)
			(size 0.4318 0.4318)
			(layers "F.Cu" "F.Mask" "F.Paste")
			(net "UPI_CPU1_CPU0_P0P1_DN<13>")
		)
		(pad "DB4" smd circle
			(at -34.98342 10.987532 270)
			(size 0.4318 0.4318)
			(layers "F.Cu" "F.Mask" "F.Paste")
			(net "GND")
		)
		(pad "DB6" smd circle
			(at -33.355534 10.987532 270)
			(size 0.4318 0.4318)
			(layers "F.Cu" "F.Mask" "F.Paste")
			(net "UPI_CPU0_CPU1_P1P0_DN<12>")
		)
		(pad "DB8" smd circle
			(at -31.727902 10.987532 270)
			(size 0.4318 0.4318)
			(layers "F.Cu" "F.Mask" "F.Paste")
			(net "GND")
		)
		(pad "DB10" smd circle
			(at -30.100016 10.987532 270)
			(size 0.4318 0.4318)
			(layers "F.Cu" "F.Mask" "F.Paste")
			(net "P5E_CPU0_PE2_RX_DP<2>")
		)
		(pad "DB12" smd circle
			(at -28.472384 10.987532 270)
			(size 0.4318 0.4318)
			(layers "F.Cu" "F.Mask" "F.Paste")
			(net "GND")
		)
		(pad "DB14" smd circle
			(at -26.844498 10.987532 270)
			(size 0.4318 0.4318)
			(layers "F.Cu" "F.Mask" "F.Paste")
			(net "P5E_CPU0_PE2_TX_DN<3>")
		)
		(pad "DB16" smd circle
			(at -25.216612 10.987532 270)
			(size 0.4318 0.4318)
			(layers "F.Cu" "F.Mask" "F.Paste")
			(net "GND")
		)
		(pad "DB18" smd circle
			(at -23.58898 10.987532 270)
			(size 0.4318 0.4318)
			(layers "F.Cu" "F.Mask" "F.Paste")
			(net "M_H_CPU0_SB_DQS_DN<3>")
		)
		(pad "DB20" smd circle
			(at -21.961094 10.987532 270)
			(size 0.4318 0.4318)
			(layers "F.Cu" "F.Mask" "F.Paste")
			(net "GND")
		)
		(pad "DB22" smd circle
			(at -20.333462 10.987532 270)
			(size 0.4318 0.4318)
			(layers "F.Cu" "F.Mask" "F.Paste")
			(net "GND")
		)
		(pad "DB24" smd circle
			(at -18.705576 10.987532 270)
			(size 0.4318 0.4318)
			(layers "F.Cu" "F.Mask" "F.Paste")
			(net "M_H_CPU0_SB_DQS_DP<1>")
		)
		(pad "DB26" smd circle
			(at -17.07769 10.987532 270)
			(size 0.4318 0.4318)
			(layers "F.Cu" "F.Mask" "F.Paste")
			(net "GND")
		)
		(pad "DB28" smd circle
			(at -15.450058 10.987532 270)
			(size 0.4318 0.4318)
			(layers "F.Cu" "F.Mask" "F.Paste")
			(net "GND")
		)
		(pad "DB30" smd circle
			(at -13.822426 10.987532 270)
			(size 0.4318 0.4318)
			(layers "F.Cu" "F.Mask" "F.Paste")
			(net "M_H_CPU0_SB_DQS_DP<0>")
		)
		(pad "DB32" smd circle
			(at -12.19454 10.987532 270)
			(size 0.4318 0.4318)
			(layers "F.Cu" "F.Mask" "F.Paste")
			(net "GND")
		)
		(pad "DB34" smd circle
			(at -10.566654 10.987532 270)
			(size 0.4318 0.4318)
			(layers "F.Cu" "F.Mask" "F.Paste")
			(net "GND")
		)
		(pad "DB36" smd circle
			(at -8.939022 10.987532 270)
			(size 0.4318 0.4318)
			(layers "F.Cu" "F.Mask" "F.Paste")
			(net "M_H_CPU0_SB_DQS_DP<9>")
		)
		(pad "DB38" smd circle
			(at -7.311136 10.987532 270)
			(size 0.4318 0.4318)
			(layers "F.Cu" "F.Mask" "F.Paste")
			(net "GND")
		)
		(pad "DB40" smd circle
			(at -5.68325 10.987532 270)
			(size 0.4318 0.4318)
			(layers "F.Cu" "F.Mask" "F.Paste")
			(net "GND")
		)
		(pad "DB42" smd circle
			(at -4.055618 10.987532 270)
			(size 0.4318 0.4318)
			(layers "F.Cu" "F.Mask" "F.Paste")
			(net "M_H_CPU0_CLK_DP<1>")
		)
		(pad "DB44" smd circle
			(at -2.427732 10.987532 270)
			(size 0.4318 0.4318)
			(layers "F.Cu" "F.Mask" "F.Paste")
			(net "GND")
		)
		(pad "DB47" smd circle
			(at 1.613916 11.097514 270)
			(size 0.4318 0.4318)
			(layers "F.Cu" "F.Mask" "F.Paste")
			(net "GND")
		)
		(pad "DB49" smd circle
			(at 3.241802 11.097514 270)
			(size 0.4318 0.4318)
			(layers "F.Cu" "F.Mask" "F.Paste")
			(net "M_H_CPU0_SA_CA<0>")
		)
		(pad "DB51" smd circle
			(at 4.869434 11.097514 270)
			(size 0.4318 0.4318)
			(layers "F.Cu" "F.Mask" "F.Paste")
			(net "GND")
		)
		(pad "DB53" smd circle
			(at 6.49732 11.097514 270)
			(size 0.4318 0.4318)
			(layers "F.Cu" "F.Mask" "F.Paste")
			(net "GND")
		)
		(pad "DB55" smd circle
			(at 8.124952 11.097514 270)
			(size 0.4318 0.4318)
			(layers "F.Cu" "F.Mask" "F.Paste")
			(net "M_H_CPU0_SA_DQS_DP<4>")
		)
		(pad "DB57" smd circle
			(at 9.752838 11.097514 270)
			(size 0.4318 0.4318)
			(layers "F.Cu" "F.Mask" "F.Paste")
			(net "GND")
		)
		(pad "DB59" smd circle
			(at 11.380724 11.097514 270)
			(size 0.4318 0.4318)
			(layers "F.Cu" "F.Mask" "F.Paste")
			(net "GND")
		)
		(pad "DB61" smd circle
			(at 13.008356 11.097514 270)
			(size 0.4318 0.4318)
			(layers "F.Cu" "F.Mask" "F.Paste")
			(net "M_H_CPU0_SA_DQS_DP<3>")
		)
		(pad "DB63" smd circle
			(at 14.635988 11.097514 270)
			(size 0.4318 0.4318)
			(layers "F.Cu" "F.Mask" "F.Paste")
			(net "GND")
		)
		(pad "DB65" smd circle
			(at 16.263874 11.097514 270)
			(size 0.4318 0.4318)
			(layers "F.Cu" "F.Mask" "F.Paste")
			(net "GND")
		)
		(pad "DB67" smd circle
			(at 17.89176 11.097514 270)
			(size 0.4318 0.4318)
			(layers "F.Cu" "F.Mask" "F.Paste")
			(net "M_H_CPU0_SA_DQS_DP<2>")
		)
		(pad "DB69" smd circle
			(at 19.519392 11.097514 270)
			(size 0.4318 0.4318)
			(layers "F.Cu" "F.Mask" "F.Paste")
			(net "GND")
		)
		(pad "DB71" smd circle
			(at 21.147278 11.097514 270)
			(size 0.4318 0.4318)
			(layers "F.Cu" "F.Mask" "F.Paste")
			(net "GND")
		)
		(pad "DB73" smd circle
			(at 22.77491 11.097514 270)
			(size 0.4318 0.4318)
			(layers "F.Cu" "F.Mask" "F.Paste")
			(net "M_H_CPU0_SA_DQS_DN<1>")
		)
		(pad "DB75" smd circle
			(at 24.402796 11.097514 270)
			(size 0.4318 0.4318)
			(layers "F.Cu" "F.Mask" "F.Paste")
			(net "GND")
		)
		(pad "DB77" smd circle
			(at 26.030682 11.097514 270)
			(size 0.4318 0.4318)
			(layers "F.Cu" "F.Mask" "F.Paste")
			(net "GND")
		)
		(pad "DB79" smd circle
			(at 27.658314 11.097514 270)
			(size 0.4318 0.4318)
			(layers "F.Cu" "F.Mask" "F.Paste")
			(net "GND")
		)
		(pad "DB81" smd circle
			(at 29.2862 11.097514 270)
			(size 0.4318 0.4318)
			(layers "F.Cu" "F.Mask" "F.Paste")
			(net "GND")
		)
		(pad "DB83" smd circle
			(at 30.914086 11.097514 270)
			(size 0.4318 0.4318)
			(layers "F.Cu" "F.Mask" "F.Paste")
			(net "GND")
		)
	)
)
